# S9S_MB_2U (Grand Teton) — schematic netlist excerpt (pin names and nets, part order shuffled) for the footprints in the layout excerpt that follows; sources: Cadence DE-HDL packaged netlist, KiCad conversion of 03242023_DA0F0TMBIJ0_F0T_Motherboard_J_brd_V01_OCP.brd

J14  SCONN288_ADR50017P087CC  SCONN288_ADR50017-P087CC IO  pkg DDR288S_1-1VXB  page 95
  VIN_BULK0  = P12V_S3_AUX_CPU0_NVDIMM
  RFU0  = TP_CHG_CPU0_DIMM2_FRU_0
  VIN_MGMT  = P3V3_AUX
  HSCL  = I3C_SPD_DDREFGH_CPU0_LVC1_SCL_5
  HSDA  = I3C_SPD_DDREFGH_CPU0_LVC1_SDA
  VSS0  = GND
  DQ0_A  = M_G_CPU0_SA_DQ<0>
  VSS1  = GND
  DQ1_A  = M_G_CPU0_SA_DQ<1>
  VSS2  = GND
  DQS0_A_T  = M_G_CPU0_SA_DQS_DP<0>
  DQS0_A_C  = M_G_CPU0_SA_DQS_DN<0>
  VSS3  = GND
  DQ4_A  = M_G_CPU0_SA_DQ<4>
  VSS4  = GND
  DQ5_A  = M_G_CPU0_SA_DQ<5>
  VSS5  = GND
  DQ8_A  = M_G_CPU0_SA_DQ<8>
  VSS6  = GND
  DQ9_A  = M_G_CPU0_SA_DQ<9>
  VSS7  = GND
  DQS1_A_T  = M_G_CPU0_SA_DQS_DP<1>
  DQS1_A_C  = M_G_CPU0_SA_DQS_DN<1>
  VSS8  = GND
  DQ12_A  = M_G_CPU0_SA_DQ<12>
  VSS9  = GND
  DQ13_A  = M_G_CPU0_SA_DQ<13>
  VSS10  = GND
  DQ16_A  = M_G_CPU0_SA_DQ<16>
  VSS11  = GND
  DQ17_A  = M_G_CPU0_SA_DQ<17>
  VSS12  = GND
  DQS2_A_T  = M_G_CPU0_SA_DQS_DP<2>
  DQS2_A_C  = M_G_CPU0_SA_DQS_DN<2>
  VSS13  = GND
  DQ20_A  = M_G_CPU0_SA_DQ<20>
  VSS14  = GND
  DQ21_A  = M_G_CPU0_SA_DQ<21>
  VSS15  = GND
  DQ24_A  = M_G_CPU0_SA_DQ<24>
  VSS16  = GND
  DQ25_A  = M_G_CPU0_SA_DQ<25>
  VSS17  = GND
  DQS3_A_T  = M_G_CPU0_SA_DQS_DP<3>
  DQS3_A_C  = M_G_CPU0_SA_DQS_DN<3>
  VSS18  = GND
  DQ28_A  = M_G_CPU0_SA_DQ<28>
  VSS19  = GND
  DQ29_A  = M_G_CPU0_SA_DQ<29>
  VSS20  = GND
  CB0_A  = M_G_CPU0_SA_CB<0>
  VSS21  = GND
  CB1_A  = M_G_CPU0_SA_CB<1>
  VSS22  = GND
  DQS4_A_T  = M_G_CPU0_SA_DQS_DP<4>
  DQS4_A_C  = M_G_CPU0_SA_DQS_DN<4>
  VSS23  = GND
  CB4_A  = M_G_CPU0_SA_CB<4>
  VSS24  = GND
  CB5_A  = M_G_CPU0_SA_CB<5>
  VSS25  = GND
  ALERT_N  = M_G_CPU0_ALERT_N
  VSS26  = GND
  CS0_A_N  = M_G_CPU0_SA_CS_N<2>
  VSS27  = GND
  CA0_A  = M_G_CPU0_SA_CA<0>
  VSS28  = GND
  CA2_A  = M_G_CPU0_SA_CA<2>
  VSS29  = GND
  CA4_A  = M_G_CPU0_SA_CA<4>
  VSS30  = GND
  CA6_A  = M_G_CPU0_SA_CA<6>
  VSS31  = GND
  PAR_A  = M_G_CPU0_SA_PAR
  VSS32  = GND
  CA0_B  = M_G_CPU0_SB_CA<0>
  VSS33  = GND
  CA2_B  = M_G_CPU0_SB_CA<2>
  VSS34  = GND
  CA4_B  = M_G_CPU0_SB_CA<4>
  VSS35  = GND
  CA6_B  = M_G_CPU0_SB_CA<6>
  VSS36  = GND
  CS0_B_N  = M_G_CPU0_SB_CS_N<2>
  VSS37  = GND
  \lbd||rsp_a_n\  = M_G_CPU0_SA_RSP<1>
  \lbs||rsp_b_n\  = M_G_CPU0_SB_RSP<1>
  VSS38  = GND
  CB4_B  = M_G_CPU0_SB_CB<4>
  VSS39  = GND
  CB5_B  = M_G_CPU0_SB_CB<5>
  VSS40  = GND
  \dqs9_b_t||tdqs9_b_t||dbi4_b_n\  = M_G_CPU0_SB_DQS_DP<9>
  \dqs9_b_c||tdqs9_b_c\  = M_G_CPU0_SB_DQS_DN<9>
  VSS41  = GND
  CB0_B  = M_G_CPU0_SB_CB<0>
  VSS42  = GND
  CB1_B  = M_G_CPU0_SB_CB<1>
  VSS43  = GND
  DQ0_B  = M_G_CPU0_SB_DQ<0>
  VSS44  = GND
  DQ1_B  = M_G_CPU0_SB_DQ<1>
  VSS45  = GND
  DQS0_B_T  = M_G_CPU0_SB_DQS_DP<0>
  DQS0_B_C  = M_G_CPU0_SB_DQS_DN<0>
  VSS46  = GND
  DQ4_B  = M_G_CPU0_SB_DQ<4>
  VSS47  = GND
  DQ5_B  = M_G_CPU0_SB_DQ<5>
  VSS48  = GND
  DQ8_B  = M_G_CPU0_SB_DQ<8>
  VSS49  = GND
  DQ9_B  = M_G_CPU0_SB_DQ<9>
  VSS50  = GND
  DQS1_B_T  = M_G_CPU0_SB_DQS_DP<1>
  DQS1_B_C  = M_G_CPU0_SB_DQS_DN<1>
  VSS51  = GND
  DQ12_B  = M_G_CPU0_SB_DQ<12>
  VSS52  = GND
  DQ13_B  = M_G_CPU0_SB_DQ<13>
  VSS53  = GND
  DQ16_B  = M_G_CPU0_SB_DQ<16>
  VSS54  = GND
  DQ17_B  = M_G_CPU0_SB_DQ<17>
  VSS55  = GND
  DQS2_B_T  = M_G_CPU0_SB_DQS_DP<2>
  DQS2_B_C  = M_G_CPU0_SB_DQS_DN<2>
  VSS56  = GND
  DQ20_B  = M_G_CPU0_SB_DQ<20>
  VSS57  = GND
  DQ21_B  = M_G_CPU0_SB_DQ<21>
  VSS58  = GND
  DQ24_B  = M_G_CPU0_SB_DQ<24>
  VSS59  = GND
  DQ25_B  = M_G_CPU0_SB_DQ<25>
  VSS60  = GND
  DQS3_B_T  = M_G_CPU0_SB_DQS_DP<3>
  DQS3_B_C  = M_G_CPU0_SB_DQS_DN<3>
  VSS61  = GND
  DQ28_B  = M_G_CPU0_SB_DQ<28>
  VSS62  = GND
  DQ29_B  = M_G_CPU0_SB_DQ<29>
  VSS63  = GND
  RFU1  = TP_CHG_CPU0_DIMM2_FRU_1
  VIN_BULK1  = P12V_S3_AUX_CPU0_NVDIMM
  VIN_BULK2  = P12V_S3_AUX_CPU0_NVDIMM
  \pwr_good||fail_n\  = PWRGD_CHG_CPU0_DIMM2
  HSA  = PD_CHG_CPU0_DIMM2_SAA
  RFU2  = TP_CHG_CPU0_DIMM2_FRU_2
  RFU3  = TP_CHG_CPU0_DIMM2_FRU_3
  VSS64  = GND
  DQ2_A  = M_G_CPU0_SA_DQ<2>
  VSS65  = GND
  DQ3_A  = M_G_CPU0_SA_DQ<3>
  VSS66  = GND
  \dqs5_a_c||tdqs5_a_c||dqs5_a_t||tdqs5_a_t\  = M_G_CPU0_SA_DQS_DN<5>
  \dqs5_a_t||tdqs5_a_t\  = M_G_CPU0_SA_DQS_DP<5>
  VSS67  = GND
  DQ6_A  = M_G_CPU0_SA_DQ<6>
  VSS68  = GND
  DQ7_A  = M_G_CPU0_SA_DQ<7>
  VSS69  = GND
  DQ10_A  = M_G_CPU0_SA_DQ<10>
  VSS70  = GND
  DQ11_A  = M_G_CPU0_SA_DQ<11>
  VSS71  = GND
  \dqs6_a_c||tdqs6_a_c||dqs6_a_t||tdqs6_a_t\  = M_G_CPU0_SA_DQS_DN<6>
  \dqs6_a_t||tdqs6_a_t\  = M_G_CPU0_SA_DQS_DP<6>
  VSS72  = GND
  DQ14_A  = M_G_CPU0_SA_DQ<14>
  VSS73  = GND
  DQ15_A  = M_G_CPU0_SA_DQ<15>
  VSS74  = GND
  DQ18_A  = M_G_CPU0_SA_DQ<18>
  VSS75  = GND
  DQ19_A  = M_G_CPU0_SA_DQ<19>
  VSS76  = GND
  \dqs7_a_c||tdqs7_a_c\  = M_G_CPU0_SA_DQS_DN<7>
  \dqs7_a_t||tdqs7_a_t\  = M_G_CPU0_SA_DQS_DP<7>
  VSS77  = GND
  DQ22_A  = M_G_CPU0_SA_DQ<22>
  VSS78  = GND
  DQ23_A  = M_G_CPU0_SA_DQ<23>
  VSS79  = GND
  DQ26_A  = M_G_CPU0_SA_DQ<26>
  VSS80  = GND
  DQ27_A  = M_G_CPU0_SA_DQ<27>
  VSS81  = GND
  \dqs8_a_c||tdqs8_a_c\  = M_G_CPU0_SA_DQS_DN<8>
  \dqs8_a_t||tdqs8_a_t\  = M_G_CPU0_SA_DQS_DP<8>
  VSS82  = GND
  DQ30_A  = M_G_CPU0_SA_DQ<30>
  VSS83  = GND
  DQ31_A  = M_G_CPU0_SA_DQ<31>
  VSS84  = GND
  CB2_A  = M_G_CPU0_SA_CB<2>
  VSS85  = GND
  CB3_A  = M_G_CPU0_SA_CB<3>
  VSS86  = GND
  \dqs9_a_c||tdqs9_a_c\  = M_G_CPU0_SA_DQS_DN<9>
  \dqs9_a_t||tdqs9_a_t\  = M_G_CPU0_SA_DQS_DP<9>
  VSS87  = GND
  CB6_A  = M_G_CPU0_SA_CB<6>
  VSS88  = GND
  CB7_A  = M_G_CPU0_SA_CB<7>
  VSS89  = GND
  RESET_N  = RST_M_GH_CPU0_FPGA_N
  VSS90  = GND
  CS1_A_N  = M_G_CPU0_SA_CS_N<3>
  VSS91  = GND
  CA1_A  = M_G_CPU0_SA_CA<1>
  VSS92  = GND
  CA3_A  = M_G_CPU0_SA_CA<3>
  VSS93  = GND
  CA5_A  = M_G_CPU0_SA_CA<5>
  VSS94  = GND
  CK_T  = M_G_CPU0_CLK_DP<1>
  CK_C  = M_G_CPU0_CLK_DN<1>
  VSS95  = GND
  RFU4  = TP_CHG_CPU0_DIMM2_FRU_4
  CA1_B  = M_G_CPU0_SB_CA<1>
  VSS96  = GND
  CA3_B  = M_G_CPU0_SB_CA<3>
  VSS97  = GND
  CA5_B  = M_G_CPU0_SB_CA<5>
  VSS98  = GND
  PAR_B  = M_G_CPU0_SB_PAR
  VSS99  = GND
  CS1_B_N  = M_G_CPU0_SB_CS_N<3>
  VSS100  = GND
  RFU5  = TP_CHG_CPU0_DIMM2_FRU_5
  RFU6  = TP_CHG_CPU0_DIMM2_FRU_6
  VSS101  = GND
  CB6_B  = M_G_CPU0_SB_CB<6>
  VSS102  = GND
  CB7_B  = M_G_CPU0_SB_CB<7>
  VSS103  = GND
  DQS4_B_C  = M_G_CPU0_SB_DQS_DN<4>
  DQS4_B_T  = M_G_CPU0_SB_DQS_DP<4>
  VSS104  = GND
  CB2_B  = M_G_CPU0_SB_CB<2>
  VSS105  = GND
  CB3_B  = M_G_CPU0_SB_CB<3>
  VSS106  = GND
  DQ2_B  = M_G_CPU0_SB_DQ<2>
  VSS107  = GND
  DQ3_B  = M_G_CPU0_SB_DQ<3>
  VSS108  = GND
  \dqs5_b_c||tdqs5_b_c\  = M_G_CPU0_SB_DQS_DN<5>
  \dqs5_b_t||tdqs5_b_t\  = M_G_CPU0_SB_DQS_DP<5>
  VSS109  = GND
  DQ6_B  = M_G_CPU0_SB_DQ<6>
  VSS110  = GND
  DQ7_B  = M_G_CPU0_SB_DQ<7>
  VSS111  = GND
  DQ10_B  = M_G_CPU0_SB_DQ<10>
  VSS112  = GND
  DQ11_B  = M_G_CPU0_SB_DQ<11>
  VSS113  = GND
  \dqs6_b_c||tdqs6_b_c\  = M_G_CPU0_SB_DQS_DN<6>
  \dqs6_b_t||tdqs6_b_t\  = M_G_CPU0_SB_DQS_DP<6>
  VSS114  = GND
  DQ14_B  = M_G_CPU0_SB_DQ<14>
  VSS115  = GND
  DQ15_B  = M_G_CPU0_SB_DQ<15>
  VSS116  = GND
  DQ18_B  = M_G_CPU0_SB_DQ<18>
  VSS117  = GND
  DQ19_B  = M_G_CPU0_SB_DQ<19>
  VSS118  = GND
  \dqs7_b_c||tdqs7_b_c\  = M_G_CPU0_SB_DQS_DN<7>
  \dqs7_b_t||tdqs7_b_t\  = M_G_CPU0_SB_DQS_DP<7>
  VSS119  = GND
  DQ22_B  = M_G_CPU0_SB_DQ<22>
  VSS120  = GND
  DQ23_B  = M_G_CPU0_SB_DQ<23>
  VSS121  = GND
  DQ26_B  = M_G_CPU0_SB_DQ<26>
  VSS122  = GND
  DQ27_B  = M_G_CPU0_SB_DQ<27>
  VSS123  = GND
  \dqs8_b_c||tdqs8_b_c\  = M_G_CPU0_SB_DQS_DN<8>
  \dqs8_b_t||tdqs8_b_t\  = M_G_CPU0_SB_DQS_DP<8>
  VSS124  = GND
  DQ30_B  = M_G_CPU0_SB_DQ<30>
  VSS125  = GND
  DQ31_B  = M_G_CPU0_SB_DQ<31>
  VSS126  = GND
  G1  = GND
  G2  = GND
  G3  = GND

(kicad_pcb
	(version 20260206)
	(generator "pcbnew")
	(generator_version "10.0")
	(general
		(thickness 1.6)
		(legacy_teardrops no)
	)
	(paper "A4")
	(title_block
		(title "03242023_DA0F0TMBIJ0_F0T_Motherboard_J_brd_V01_OCP.brd")
		(comment 1 "Grand Teton / footprint 3833 of 6105 (J14), pads 1-45 of 291")
	)
	(layers
		(0 "F.Cu" signal "TOP")
		(4 "In1.Cu" signal "GND")
		(6 "In2.Cu" signal "IN1")
		(8 "In3.Cu" signal "GND1")
		(10 "In4.Cu" signal "IN2")
		(12 "In5.Cu" signal "GND2")
		(14 "In6.Cu" signal "IN3")
		(16 "In7.Cu" signal "GND3")
		(18 "In8.Cu" signal "VCC")
		(20 "In9.Cu" signal "VCC1")
		(22 "In10.Cu" signal "GND4")
		(24 "In11.Cu" signal "IN4")
		(26 "In12.Cu" signal "GND5")
		(28 "In13.Cu" signal "IN5")
		(30 "In14.Cu" signal "GND6")
		(32 "In15.Cu" signal "IN6")
		(34 "In16.Cu" signal "GND7")
		(2 "B.Cu" signal "BOTTOM")
		(9 "F.Adhes" user "F.Adhesive")
		(11 "B.Adhes" user "B.Adhesive")
		(13 "F.Paste" user "Package Geometry/Pastemask Top")
		(15 "B.Paste" user "Package Geometry/Pastemask Bottom")
		(5 "F.SilkS" user "Ref Des/Silkscreen Top")
		(7 "B.SilkS" user "Ref Des/Silkscreen Bottom")
		(1 "F.Mask" user "Board Geometry/Soldermask Top")
		(3 "B.Mask" user "Board Geometry/Soldermask Bottom")
		(17 "Dwgs.User" user "User.Drawings")
		(19 "Cmts.User" user "User.Comments")
		(21 "Eco1.User" user "User.Eco1")
		(23 "Eco2.User" user "User.Eco2")
		(25 "Edge.Cuts" user "Board Geometry/Outline")
		(27 "Margin" user)
		(31 "F.CrtYd" user "Package Geometry/Place Bound Top")
		(29 "B.CrtYd" user "Package Geometry/Place Bound Bottom")
		(35 "F.Fab" user "Ref Des/Assembly Top")
		(33 "B.Fab" user "Ref Des/Assembly Bottom")
	)
	(footprint ""
		(layer "F.Cu")
		(at 438.978548 -258.091686)
		(property "Reference" "J14"
			(at -3.683 -81.702148 0)
			(unlocked yes)
			(layer "F.SilkS")
			(effects
				(font
					(size 0.7874 0.5842)
					(thickness 0.1524)
				)
				(justify left)
			)
		)
		(property "Value" ""
			(at 0 0 0)
			(layer "F.Fab")
			(effects
				(font
					(size 1.27 1.27)
				)
			)
		)
		(duplicate_pad_numbers_are_jumpers no)
		(pad "1" smd rect
			(at -2.050034 -63.324994 270)
			(size 0.519938 1.4986)
			(layers "F.Cu" "F.Mask" "F.Paste")
			(net "P12V_S3_AUX_CPU0_NVDIMM")
		)
		(pad "2" smd rect
			(at -2.050034 -62.47511 270)
			(size 0.519938 1.4986)
			(layers "F.Cu" "F.Mask" "F.Paste")
			(net "TP_CHG_CPU0_DIMM2_FRU_0")
		)
		(pad "3" smd rect
			(at -2.050034 -61.624972 270)
			(size 0.519938 1.4986)
			(layers "F.Cu" "F.Mask" "F.Paste")
			(net "P3V3_AUX")
		)
		(pad "4" smd rect
			(at -2.050034 -60.775088 270)
			(size 0.519938 1.4986)
			(layers "F.Cu" "F.Mask" "F.Paste")
			(net "I3C_SPD_DDREFGH_CPU0_LVC1_SCL_5")
		)
		(pad "5" smd rect
			(at -2.050034 -59.92495 270)
			(size 0.519938 1.4986)
			(layers "F.Cu" "F.Mask" "F.Paste")
			(net "I3C_SPD_DDREFGH_CPU0_LVC1_SDA")
		)
		(pad "6" smd rect
			(at -2.050034 -59.075066 270)
			(size 0.519938 1.4986)
			(layers "F.Cu" "F.Mask" "F.Paste")
			(net "GND")
		)
		(pad "7" smd rect
			(at -2.050034 -58.224928 270)
			(size 0.519938 1.4986)
			(layers "F.Cu" "F.Mask" "F.Paste")
			(net "M_G_CPU0_SA_DQ<0>")
		)
		(pad "8" smd rect
			(at -2.050034 -57.375044 270)
			(size 0.519938 1.4986)
			(layers "F.Cu" "F.Mask" "F.Paste")
			(net "GND")
		)
		(pad "9" smd rect
			(at -2.050034 -56.524906 270)
			(size 0.519938 1.4986)
			(layers "F.Cu" "F.Mask" "F.Paste")
			(net "M_G_CPU0_SA_DQ<1>")
		)
		(pad "10" smd rect
			(at -2.050034 -55.675022 270)
			(size 0.519938 1.4986)
			(layers "F.Cu" "F.Mask" "F.Paste")
			(net "GND")
		)
		(pad "11" smd rect
			(at -2.050034 -54.824884 270)
			(size 0.519938 1.4986)
			(layers "F.Cu" "F.Mask" "F.Paste")
			(net "M_G_CPU0_SA_DQS_DP<0>")
		)
		(pad "12" smd rect
			(at -2.050034 -53.975 270)
			(size 0.519938 1.4986)
			(layers "F.Cu" "F.Mask" "F.Paste")
			(net "M_G_CPU0_SA_DQS_DN<0>")
		)
		(pad "13" smd rect
			(at -2.050034 -53.125116 270)
			(size 0.519938 1.4986)
			(layers "F.Cu" "F.Mask" "F.Paste")
			(net "GND")
		)
		(pad "14" smd rect
			(at -2.050034 -52.274978 270)
			(size 0.519938 1.4986)
			(layers "F.Cu" "F.Mask" "F.Paste")
			(net "M_G_CPU0_SA_DQ<4>")
		)
		(pad "15" smd rect
			(at -2.050034 -51.425094 270)
			(size 0.519938 1.4986)
			(layers "F.Cu" "F.Mask" "F.Paste")
			(net "GND")
		)
		(pad "16" smd rect
			(at -2.050034 -50.574956 270)
			(size 0.519938 1.4986)
			(layers "F.Cu" "F.Mask" "F.Paste")
			(net "M_G_CPU0_SA_DQ<5>")
		)
		(pad "17" smd rect
			(at -2.050034 -49.725072 270)
			(size 0.519938 1.4986)
			(layers "F.Cu" "F.Mask" "F.Paste")
			(net "GND")
		)
		(pad "18" smd rect
			(at -2.050034 -48.874934 270)
			(size 0.519938 1.4986)
			(layers "F.Cu" "F.Mask" "F.Paste")
			(net "M_G_CPU0_SA_DQ<8>")
		)
		(pad "19" smd rect
			(at -2.050034 -48.02505 270)
			(size 0.519938 1.4986)
			(layers "F.Cu" "F.Mask" "F.Paste")
			(net "GND")
		)
		(pad "20" smd rect
			(at -2.050034 -47.174912 270)
			(size 0.519938 1.4986)
			(layers "F.Cu" "F.Mask" "F.Paste")
			(net "M_G_CPU0_SA_DQ<9>")
		)
		(pad "21" smd rect
			(at -2.050034 -46.325028 270)
			(size 0.519938 1.4986)
			(layers "F.Cu" "F.Mask" "F.Paste")
			(net "GND")
		)
		(pad "22" smd rect
			(at -2.050034 -45.47489 270)
			(size 0.519938 1.4986)
			(layers "F.Cu" "F.Mask" "F.Paste")
			(net "M_G_CPU0_SA_DQS_DP<1>")
		)
		(pad "23" smd rect
			(at -2.050034 -44.625006 270)
			(size 0.519938 1.4986)
			(layers "F.Cu" "F.Mask" "F.Paste")
			(net "M_G_CPU0_SA_DQS_DN<1>")
		)
		(pad "24" smd rect
			(at -2.050034 -43.775122 270)
			(size 0.519938 1.4986)
			(layers "F.Cu" "F.Mask" "F.Paste")
			(net "GND")
		)
		(pad "25" smd rect
			(at -2.050034 -42.924984 270)
			(size 0.519938 1.4986)
			(layers "F.Cu" "F.Mask" "F.Paste")
			(net "M_G_CPU0_SA_DQ<12>")
		)
		(pad "26" smd rect
			(at -2.050034 -42.0751 270)
			(size 0.519938 1.4986)
			(layers "F.Cu" "F.Mask" "F.Paste")
			(net "GND")
		)
		(pad "27" smd rect
			(at -2.050034 -41.224962 270)
			(size 0.519938 1.4986)
			(layers "F.Cu" "F.Mask" "F.Paste")
			(net "M_G_CPU0_SA_DQ<13>")
		)
		(pad "28" smd rect
			(at -2.050034 -40.375078 270)
			(size 0.519938 1.4986)
			(layers "F.Cu" "F.Mask" "F.Paste")
			(net "GND")
		)
		(pad "29" smd rect
			(at -2.050034 -39.52494 270)
			(size 0.519938 1.4986)
			(layers "F.Cu" "F.Mask" "F.Paste")
			(net "M_G_CPU0_SA_DQ<16>")
		)
		(pad "30" smd rect
			(at -2.050034 -38.675056 270)
			(size 0.519938 1.4986)
			(layers "F.Cu" "F.Mask" "F.Paste")
			(net "GND")
		)
		(pad "31" smd rect
			(at -2.050034 -37.824918 270)
			(size 0.519938 1.4986)
			(layers "F.Cu" "F.Mask" "F.Paste")
			(net "M_G_CPU0_SA_DQ<17>")
		)
		(pad "32" smd rect
			(at -2.050034 -36.975034 270)
			(size 0.519938 1.4986)
			(layers "F.Cu" "F.Mask" "F.Paste")
			(net "GND")
		)
		(pad "33" smd rect
			(at -2.050034 -36.124896 270)
			(size 0.519938 1.4986)
			(layers "F.Cu" "F.Mask" "F.Paste")
			(net "M_G_CPU0_SA_DQS_DP<2>")
		)
		(pad "34" smd rect
			(at -2.050034 -35.275012 270)
			(size 0.519938 1.4986)
			(layers "F.Cu" "F.Mask" "F.Paste")
			(net "M_G_CPU0_SA_DQS_DN<2>")
		)
		(pad "35" smd rect
			(at -2.050034 -34.425128 270)
			(size 0.519938 1.4986)
			(layers "F.Cu" "F.Mask" "F.Paste")
			(net "GND")
		)
		(pad "36" smd rect
			(at -2.050034 -33.57499 270)
			(size 0.519938 1.4986)
			(layers "F.Cu" "F.Mask" "F.Paste")
			(net "M_G_CPU0_SA_DQ<20>")
		)
		(pad "37" smd rect
			(at -2.050034 -32.725106 270)
			(size 0.519938 1.4986)
			(layers "F.Cu" "F.Mask" "F.Paste")
			(net "GND")
		)
		(pad "38" smd rect
			(at -2.050034 -31.874968 270)
			(size 0.519938 1.4986)
			(layers "F.Cu" "F.Mask" "F.Paste")
			(net "M_G_CPU0_SA_DQ<21>")
		)
		(pad "39" smd rect
			(at -2.050034 -31.025084 270)
			(size 0.519938 1.4986)
			(layers "F.Cu" "F.Mask" "F.Paste")
			(net "GND")
		)
		(pad "40" smd rect
			(at -2.050034 -30.174946 270)
			(size 0.519938 1.4986)
			(layers "F.Cu" "F.Mask" "F.Paste")
			(net "M_G_CPU0_SA_DQ<24>")
		)
		(pad "41" smd rect
			(at -2.050034 -29.325062 270)
			(size 0.519938 1.4986)
			(layers "F.Cu" "F.Mask" "F.Paste")
			(net "GND")
		)
		(pad "42" smd rect
			(at -2.050034 -28.474924 270)
			(size 0.519938 1.4986)
			(layers "F.Cu" "F.Mask" "F.Paste")
			(net "M_G_CPU0_SA_DQ<25>")
		)
		(pad "43" smd rect
			(at -2.050034 -27.62504 270)
			(size 0.519938 1.4986)
			(layers "F.Cu" "F.Mask" "F.Paste")
			(net "GND")
		)
		(pad "44" smd rect
			(at -2.050034 -26.774902 270)
			(size 0.519938 1.4986)
			(layers "F.Cu" "F.Mask" "F.Paste")
			(net "M_G_CPU0_SA_DQS_DP<3>")
		)
		(pad "45" smd rect
			(at -2.050034 -25.925018 270)
			(size 0.519938 1.4986)
			(layers "F.Cu" "F.Mask" "F.Paste")
			(net "M_G_CPU0_SA_DQS_DN<3>")
		)
	)
)
